# SCM (Grand Teton) — schematic netlist excerpt (pin names and nets, part order shuffled) for the footprints in the layout excerpt that follows; sources: Cadence DE-HDL packaged netlist, KiCad conversion of 12092022_DA0F0TMDCD0_F0T_Management_Board_D_brd_V3_OCP.brd

PC213  Q_CAP  22UF 10V 20% X6S  pkg C0805  page 51 : A = P5V_AUX ; B = GND
PL4  Q_INDUCTOR  BLM18SN220TN1D/8000MA IND  pkg SMLF  page 51 : \1\ = P12V_AUX ; \2\ = SW_P5V_AUX_FLT

(kicad_pcb
	(version 20260206)
	(generator "pcbnew")
	(generator_version "10.0")
	(general
		(thickness 1.6)
		(legacy_teardrops no)
	)
	(paper "A4")
	(title_block
		(title "12092022_DA0F0TMDCD0_F0T_Management_Board_D_brd_V3_OCP.brd")
		(comment 1 "Grand Teton / footprints 199-200 of 1440")
	)
	(layers
		(0 "F.Cu" signal "TOP")
		(4 "In1.Cu" signal "GND")
		(6 "In2.Cu" signal "IN1")
		(8 "In3.Cu" signal "GND1")
		(10 "In4.Cu" signal "IN2")
		(12 "In5.Cu" signal "VCC")
		(14 "In6.Cu" signal "VCC1")
		(16 "In7.Cu" signal "IN3")
		(18 "In8.Cu" signal "GND2")
		(20 "In9.Cu" signal "IN4")
		(22 "In10.Cu" signal "GND3")
		(2 "B.Cu" signal "BOTTOM")
		(9 "F.Adhes" user "F.Adhesive")
		(11 "B.Adhes" user "B.Adhesive")
		(13 "F.Paste" user "Package Geometry/Pastemask Top")
		(15 "B.Paste" user "Package Geometry/Pastemask Bottom")
		(5 "F.SilkS" user "Ref Des/Silkscreen Top")
		(7 "B.SilkS" user "Ref Des/Silkscreen Bottom")
		(1 "F.Mask" user "Board Geometry/Soldermask Top")
		(3 "B.Mask" user "Board Geometry/Soldermask Bottom")
		(17 "Dwgs.User" user "User.Drawings")
		(19 "Cmts.User" user "User.Comments")
		(21 "Eco1.User" user "User.Eco1")
		(23 "Eco2.User" user "User.Eco2")
		(25 "Edge.Cuts" user "Board Geometry/Outline")
		(27 "Margin" user)
		(31 "F.CrtYd" user "Package Geometry/Place Bound Top")
		(29 "B.CrtYd" user "Package Geometry/Place Bound Bottom")
		(35 "F.Fab" user "Ref Des/Assembly Top")
		(33 "B.Fab" user "Ref Des/Assembly Bottom")
	)
	(footprint ""
		(layer "F.Cu")
		(at 6.858 -57.404)
		(property "Reference" "PL4"
			(at 0 0 0)
			(layer "F.SilkS")
			(hide yes)
			(effects
				(font
					(size 1.27 1.27)
				)
			)
		)
		(property "Value" ""
			(at 0 0 0)
			(layer "F.Fab")
			(effects
				(font
					(size 1.27 1.27)
				)
			)
		)
		(duplicate_pad_numbers_are_jumpers no)
		(fp_line
			(start -1.27 -0.5842)
			(end 1.27 -0.5842)
			(stroke
				(width 0.1524)
				(type default)
			)
			(layer "F.SilkS")
		)
		(fp_line
			(start -1.27 -0.5588)
			(end -1.27 -0.5842)
			(stroke
				(width 0.1524)
				(type default)
			)
			(layer "F.SilkS")
		)
		(fp_line
			(start -1.27 0.5842)
			(end -1.27 -0.5842)
			(stroke
				(width 0.1524)
				(type default)
			)
			(layer "F.SilkS")
		)
		(fp_line
			(start -0.127 0.5842)
			(end -0.127 -0.5842)
			(stroke
				(width 0.1524)
				(type default)
			)
			(layer "F.SilkS")
		)
		(fp_line
			(start 0.127 0.5842)
			(end 0.127 -0.5842)
			(stroke
				(width 0.1524)
				(type default)
			)
			(layer "F.SilkS")
		)
		(fp_line
			(start 1.27 0.5842)
			(end -1.27 0.5842)
			(stroke
				(width 0.1524)
				(type default)
			)
			(layer "F.SilkS")
		)
		(fp_line
			(start 1.27 0.5842)
			(end 1.27 -0.5842)
			(stroke
				(width 0.1524)
				(type default)
			)
			(layer "F.SilkS")
		)
		(fp_line
			(start -1.194308 -0.406654)
			(end -0.9144 -0.406654)
			(stroke
				(width 0.1)
				(type default)
			)
			(layer "F.Fab")
		)
		(fp_line
			(start -1.194308 0.406654)
			(end -1.194308 -0.406654)
			(stroke
				(width 0.1)
				(type default)
			)
			(layer "F.Fab")
		)
		(fp_line
			(start -0.9144 -0.508)
			(end 0.9144 -0.508)
			(stroke
				(width 0.1)
				(type default)
			)
			(layer "F.Fab")
		)
		(fp_line
			(start -0.9144 -0.406654)
			(end -0.9144 -0.508)
			(stroke
				(width 0.1)
				(type default)
			)
			(layer "F.Fab")
		)
		(fp_line
			(start -0.9144 0.406654)
			(end -1.194308 0.406654)
			(stroke
				(width 0.1)
				(type default)
			)
			(layer "F.Fab")
		)
		(fp_line
			(start -0.9144 0.508)
			(end -0.9144 0.406654)
			(stroke
				(width 0.1)
				(type default)
			)
			(layer "F.Fab")
		)
		(fp_line
			(start 0.9144 -0.508)
			(end 0.9144 -0.406654)
			(stroke
				(width 0.1)
				(type default)
			)
			(layer "F.Fab")
		)
		(fp_line
			(start 0.9144 -0.406654)
			(end 1.1938 -0.406654)
			(stroke
				(width 0.1)
				(type default)
			)
			(layer "F.Fab")
		)
		(fp_line
			(start 0.9144 0.4064)
			(end 0.9144 0.508)
			(stroke
				(width 0.1)
				(type default)
			)
			(layer "F.Fab")
		)
		(fp_line
			(start 0.9144 0.508)
			(end -0.9144 0.508)
			(stroke
				(width 0.1)
				(type default)
			)
			(layer "F.Fab")
		)
		(fp_line
			(start 1.1938 -0.406654)
			(end 1.1938 0.4064)
			(stroke
				(width 0.1)
				(type default)
			)
			(layer "F.Fab")
		)
		(fp_line
			(start 1.1938 0.4064)
			(end 0.9144 0.4064)
			(stroke
				(width 0.1)
				(type default)
			)
			(layer "F.Fab")
		)
		(pad "1" smd rect
			(at -0.7366 0 270)
			(size 0.7112 0.8128)
			(layers "F.Cu" "F.Mask" "F.Paste")
			(net "P12V_AUX")
		)
		(pad "2" smd rect
			(at 0.7366 0 270)
			(size 0.7112 0.8128)
			(layers "F.Cu" "F.Mask" "F.Paste")
			(net "SW_P5V_AUX_FLT")
		)
	)
	(footprint ""
		(layer "F.Cu")
		(at 7.112 -31.837122 -90)
		(property "Reference" "PC213"
			(at 0 0 270)
			(layer "F.SilkS")
			(hide yes)
			(effects
				(font
					(size 1.27 1.27)
				)
			)
		)
		(property "Value" ""
			(at 0 0 270)
			(layer "F.Fab")
			(effects
				(font
					(size 1.27 1.27)
				)
			)
		)
		(duplicate_pad_numbers_are_jumpers no)
		(fp_line
			(start -1.651 0.8382)
			(end -1.651 -0.8382)
			(stroke
				(width 0.1524)
				(type default)
			)
			(layer "F.SilkS")
		)
		(fp_line
			(start 0 0.8382)
			(end 0 -0.8382)
			(stroke
				(width 0.1524)
				(type default)
			)
			(layer "F.SilkS")
		)
		(fp_line
			(start 1.651 0.8382)
			(end -1.651 0.8382)
			(stroke
				(width 0.1524)
				(type default)
			)
			(layer "F.SilkS")
		)
		(fp_line
			(start -1.651 -0.8382)
			(end 1.651 -0.8382)
			(stroke
				(width 0.1524)
				(type default)
			)
			(layer "F.SilkS")
		)
		(fp_line
			(start 1.651 -0.8382)
			(end 1.651 0.8382)
			(stroke
				(width 0.1524)
				(type default)
			)
			(layer "F.SilkS")
		)
		(fp_line
			(start -1.55956 0.7366)
			(end -1.524 0.7366)
			(stroke
				(width 0.1)
				(type default)
			)
			(layer "F.Fab")
		)
		(fp_line
			(start -1.524 0.7366)
			(end 1.524 0.7366)
			(stroke
				(width 0.1)
				(type default)
			)
			(layer "F.Fab")
		)
		(fp_line
			(start 1.524 0.7366)
			(end 1.55956 0.7366)
			(stroke
				(width 0.1)
				(type default)
			)
			(layer "F.Fab")
		)
		(fp_line
			(start 1.55956 0.7366)
			(end 1.55956 -0.7366)
			(stroke
				(width 0.1)
				(type default)
			)
			(layer "F.Fab")
		)
		(fp_line
			(start -1.55956 -0.7366)
			(end -1.55956 0.7366)
			(stroke
				(width 0.1)
				(type default)
			)
			(layer "F.Fab")
		)
		(fp_line
			(start -1.524 -0.7366)
			(end -1.55956 -0.7366)
			(stroke
				(width 0.1)
				(type default)
			)
			(layer "F.Fab")
		)
		(fp_line
			(start 1.524 -0.7366)
			(end -1.524 -0.7366)
			(stroke
				(width 0.1)
				(type default)
			)
			(layer "F.Fab")
		)
		(fp_line
			(start 1.55956 -0.7366)
			(end 1.524 -0.7366)
			(stroke
				(width 0.1)
				(type default)
			)
			(layer "F.Fab")
		)
		(pad "1" smd rect
			(at -0.94996 0 90)
			(size 1.1176 1.3716)
			(layers "F.Cu" "F.Mask" "F.Paste")
			(net "P5V_AUX")
		)
		(pad "2" smd rect
			(at 0.94996 0 90)
			(size 1.1176 1.3716)
			(layers "F.Cu" "F.Mask" "F.Paste")
			(net "GND")
		)
	)
)
